# SCM (Grand Teton) — schematic netlist excerpt (pin names and nets, part order shuffled) for the footprints in the layout excerpt that follows; sources: Cadence DE-HDL packaged netlist, KiCad conversion of 12092022_DA0F0TMDCD0_F0T_Management_Board_D_brd_V3_OCP.brd

R864  Q_RES  33.2 1% CHIP  pkg 0402LF  page 44 : A = SPI_SYS_CS0_N ; B = SPI_PCH_SECURE_CS0_N
R753  Q_RES  4.7K 1% EMPTY  pkg 0402LF  page 27 : A = P3V3_AUX ; B = SPI_BMC_BOOT_MISO

(kicad_pcb
	(version 20260206)
	(generator "pcbnew")
	(generator_version "10.0")
	(general
		(thickness 1.6)
		(legacy_teardrops no)
	)
	(paper "A4")
	(title_block
		(title "12092022_DA0F0TMDCD0_F0T_Management_Board_D_brd_V3_OCP.brd")
		(comment 1 "Grand Teton / footprints 326-327 of 1440")
	)
	(layers
		(0 "F.Cu" signal "TOP")
		(4 "In1.Cu" signal "GND")
		(6 "In2.Cu" signal "IN1")
		(8 "In3.Cu" signal "GND1")
		(10 "In4.Cu" signal "IN2")
		(12 "In5.Cu" signal "VCC")
		(14 "In6.Cu" signal "VCC1")
		(16 "In7.Cu" signal "IN3")
		(18 "In8.Cu" signal "GND2")
		(20 "In9.Cu" signal "IN4")
		(22 "In10.Cu" signal "GND3")
		(2 "B.Cu" signal "BOTTOM")
		(9 "F.Adhes" user "F.Adhesive")
		(11 "B.Adhes" user "B.Adhesive")
		(13 "F.Paste" user "Package Geometry/Pastemask Top")
		(15 "B.Paste" user "Package Geometry/Pastemask Bottom")
		(5 "F.SilkS" user "Ref Des/Silkscreen Top")
		(7 "B.SilkS" user "Ref Des/Silkscreen Bottom")
		(1 "F.Mask" user "Board Geometry/Soldermask Top")
		(3 "B.Mask" user "Board Geometry/Soldermask Bottom")
		(17 "Dwgs.User" user "User.Drawings")
		(19 "Cmts.User" user "User.Comments")
		(21 "Eco1.User" user "User.Eco1")
		(23 "Eco2.User" user "User.Eco2")
		(25 "Edge.Cuts" user "Board Geometry/Outline")
		(27 "Margin" user)
		(31 "F.CrtYd" user "Package Geometry/Place Bound Top")
		(29 "B.CrtYd" user "Package Geometry/Place Bound Bottom")
		(35 "F.Fab" user "Ref Des/Assembly Top")
		(33 "B.Fab" user "Ref Des/Assembly Bottom")
	)
	(footprint ""
		(layer "F.Cu")
		(at 58.039 -84.709 90)
		(property "Reference" "R753"
			(at 0 0 90)
			(layer "F.SilkS")
			(hide yes)
			(effects
				(font
					(size 1.27 1.27)
				)
			)
		)
		(property "Value" ""
			(at 0 0 90)
			(layer "F.Fab")
			(effects
				(font
					(size 1.27 1.27)
				)
			)
		)
		(duplicate_pad_numbers_are_jumpers no)
		(fp_line
			(start 0.7874 -0.4064)
			(end 0.7874 0.4064)
			(stroke
				(width 0.1524)
				(type default)
			)
			(layer "F.SilkS")
		)
		(fp_line
			(start -0.7874 -0.4064)
			(end 0.7874 -0.4064)
			(stroke
				(width 0.1524)
				(type default)
			)
			(layer "F.SilkS")
		)
		(fp_line
			(start 0.7874 0.4064)
			(end -0.7874 0.4064)
			(stroke
				(width 0.1524)
				(type default)
			)
			(layer "F.SilkS")
		)
		(fp_line
			(start -0.7874 0.4064)
			(end -0.7874 -0.4064)
			(stroke
				(width 0.1524)
				(type default)
			)
			(layer "F.SilkS")
		)
		(fp_line
			(start -0.12065 -0.305054)
			(end -0.12065 -0.2794)
			(stroke
				(width 0.1)
				(type default)
			)
			(layer "F.Fab")
		)
		(fp_line
			(start -0.67945 -0.305054)
			(end -0.12065 -0.305054)
			(stroke
				(width 0.1)
				(type default)
			)
			(layer "F.Fab")
		)
		(fp_line
			(start 0.67945 -0.3048)
			(end 0.67945 0.3048)
			(stroke
				(width 0.1)
				(type default)
			)
			(layer "F.Fab")
		)
		(fp_line
			(start 0.12065 -0.3048)
			(end 0.67945 -0.3048)
			(stroke
				(width 0.1)
				(type default)
			)
			(layer "F.Fab")
		)
		(fp_line
			(start 0.12065 -0.2794)
			(end 0.12065 -0.3048)
			(stroke
				(width 0.1)
				(type default)
			)
			(layer "F.Fab")
		)
		(fp_line
			(start -0.12065 -0.2794)
			(end 0.12065 -0.2794)
			(stroke
				(width 0.1)
				(type default)
			)
			(layer "F.Fab")
		)
		(fp_line
			(start 0.120396 0.2794)
			(end -0.12065 0.2794)
			(stroke
				(width 0.1)
				(type default)
			)
			(layer "F.Fab")
		)
		(fp_line
			(start -0.12065 0.2794)
			(end -0.12065 0.3048)
			(stroke
				(width 0.1)
				(type default)
			)
			(layer "F.Fab")
		)
		(fp_line
			(start 0.67945 0.3048)
			(end 0.120396 0.3048)
			(stroke
				(width 0.1)
				(type default)
			)
			(layer "F.Fab")
		)
		(fp_line
			(start 0.120396 0.3048)
			(end 0.120396 0.2794)
			(stroke
				(width 0.1)
				(type default)
			)
			(layer "F.Fab")
		)
		(fp_line
			(start -0.12065 0.3048)
			(end -0.67945 0.3048)
			(stroke
				(width 0.1)
				(type default)
			)
			(layer "F.Fab")
		)
		(fp_line
			(start -0.67945 0.3048)
			(end -0.67945 -0.305054)
			(stroke
				(width 0.1)
				(type default)
			)
			(layer "F.Fab")
		)
		(pad "1" smd circle
			(at -0.40005 0 90)
			(size 0 0)
			(layers "F.Cu" "F.Mask" "F.Paste")
			(net "P3V3_AUX")
		)
		(pad "2" smd circle
			(at 0.40005 0 90)
			(size 0 0)
			(layers "F.Cu" "F.Mask" "F.Paste")
			(net "SPI_BMC_BOOT_MISO")
		)
	)
	(footprint ""
		(layer "F.Cu")
		(at 55.7784 -109.3978 -90)
		(property "Reference" "R864"
			(at 0 0 270)
			(layer "F.SilkS")
			(hide yes)
			(effects
				(font
					(size 1.27 1.27)
				)
			)
		)
		(property "Value" ""
			(at 0 0 270)
			(layer "F.Fab")
			(effects
				(font
					(size 1.27 1.27)
				)
			)
		)
		(duplicate_pad_numbers_are_jumpers no)
		(fp_line
			(start -0.7874 0.4064)
			(end -0.7874 -0.4064)
			(stroke
				(width 0.1524)
				(type default)
			)
			(layer "F.SilkS")
		)
		(fp_line
			(start 0.7874 0.4064)
			(end -0.7874 0.4064)
			(stroke
				(width 0.1524)
				(type default)
			)
			(layer "F.SilkS")
		)
		(fp_line
			(start -0.7874 -0.4064)
			(end 0.7874 -0.4064)
			(stroke
				(width 0.1524)
				(type default)
			)
			(layer "F.SilkS")
		)
		(fp_line
			(start 0.7874 -0.4064)
			(end 0.7874 0.4064)
			(stroke
				(width 0.1524)
				(type default)
			)
			(layer "F.SilkS")
		)
		(fp_line
			(start -0.67945 0.3048)
			(end -0.67945 -0.305054)
			(stroke
				(width 0.1)
				(type default)
			)
			(layer "F.Fab")
		)
		(fp_line
			(start -0.12065 0.3048)
			(end -0.67945 0.3048)
			(stroke
				(width 0.1)
				(type default)
			)
			(layer "F.Fab")
		)
		(fp_line
			(start 0.120396 0.3048)
			(end 0.120396 0.2794)
			(stroke
				(width 0.1)
				(type default)
			)
			(layer "F.Fab")
		)
		(fp_line
			(start 0.67945 0.3048)
			(end 0.120396 0.3048)
			(stroke
				(width 0.1)
				(type default)
			)
			(layer "F.Fab")
		)
		(fp_line
			(start -0.12065 0.2794)
			(end -0.12065 0.3048)
			(stroke
				(width 0.1)
				(type default)
			)
			(layer "F.Fab")
		)
		(fp_line
			(start 0.120396 0.2794)
			(end -0.12065 0.2794)
			(stroke
				(width 0.1)
				(type default)
			)
			(layer "F.Fab")
		)
		(fp_line
			(start -0.12065 -0.2794)
			(end 0.12065 -0.2794)
			(stroke
				(width 0.1)
				(type default)
			)
			(layer "F.Fab")
		)
		(fp_line
			(start 0.12065 -0.2794)
			(end 0.12065 -0.3048)
			(stroke
				(width 0.1)
				(type default)
			)
			(layer "F.Fab")
		)
		(fp_line
			(start 0.12065 -0.3048)
			(end 0.67945 -0.3048)
			(stroke
				(width 0.1)
				(type default)
			)
			(layer "F.Fab")
		)
		(fp_line
			(start 0.67945 -0.3048)
			(end 0.67945 0.3048)
			(stroke
				(width 0.1)
				(type default)
			)
			(layer "F.Fab")
		)
		(fp_line
			(start -0.67945 -0.305054)
			(end -0.12065 -0.305054)
			(stroke
				(width 0.1)
				(type default)
			)
			(layer "F.Fab")
		)
		(fp_line
			(start -0.12065 -0.305054)
			(end -0.12065 -0.2794)
			(stroke
				(width 0.1)
				(type default)
			)
			(layer "F.Fab")
		)
		(pad "1" smd circle
			(at -0.40005 0 270)
			(size 0 0)
			(layers "F.Cu" "F.Mask" "F.Paste")
			(net "SPI_SYS_CS0_N")
		)
		(pad "2" smd circle
			(at 0.40005 0 270)
			(size 0 0)
			(layers "F.Cu" "F.Mask" "F.Paste")
			(net "SPI_PCH_SECURE_CS0_N")
		)
	)
)
